# SCM (Grand Teton) — schematic netlist excerpt (pin names and nets, part order shuffled) for the footprints in the layout excerpt that follows; sources: Cadence DE-HDL packaged netlist, KiCad conversion of 12092022_DA0F0TMDCD0_F0T_Management_Board_D_brd_V3_OCP.brd

R583  Q_RES  33.2 1% CHIP  pkg 0402LF  page 12 : A = SMB_BMC_MM10_R_SCL ; B = SMB_BMC_MM10_SCL

U23  74LVC1G07W57  74LVC1G07W5-7 IC  pkg SOT25-5_0-95_3X1-6  page 28
  NC1  = NC
  A  = DEBUG_PORT_PRSNT
  GND  = GND
  Y  = DEBUG_PORT_PRSNT_BUF_R_EN
  VCC  = P3V3_AUX

(kicad_pcb
	(version 20260206)
	(generator "pcbnew")
	(generator_version "10.0")
	(general
		(thickness 1.6)
		(legacy_teardrops no)
	)
	(paper "A4")
	(title_block
		(title "12092022_DA0F0TMDCD0_F0T_Management_Board_D_brd_V3_OCP.brd")
		(comment 1 "Grand Teton / footprints 835-836 of 1440")
	)
	(layers
		(0 "F.Cu" signal "TOP")
		(4 "In1.Cu" signal "GND")
		(6 "In2.Cu" signal "IN1")
		(8 "In3.Cu" signal "GND1")
		(10 "In4.Cu" signal "IN2")
		(12 "In5.Cu" signal "VCC")
		(14 "In6.Cu" signal "VCC1")
		(16 "In7.Cu" signal "IN3")
		(18 "In8.Cu" signal "GND2")
		(20 "In9.Cu" signal "IN4")
		(22 "In10.Cu" signal "GND3")
		(2 "B.Cu" signal "BOTTOM")
		(9 "F.Adhes" user "F.Adhesive")
		(11 "B.Adhes" user "B.Adhesive")
		(13 "F.Paste" user "Package Geometry/Pastemask Top")
		(15 "B.Paste" user "Package Geometry/Pastemask Bottom")
		(5 "F.SilkS" user "Ref Des/Silkscreen Top")
		(7 "B.SilkS" user "Ref Des/Silkscreen Bottom")
		(1 "F.Mask" user "Board Geometry/Soldermask Top")
		(3 "B.Mask" user "Board Geometry/Soldermask Bottom")
		(17 "Dwgs.User" user "User.Drawings")
		(19 "Cmts.User" user "User.Comments")
		(21 "Eco1.User" user "User.Eco1")
		(23 "Eco2.User" user "User.Eco2")
		(25 "Edge.Cuts" user "Board Geometry/Outline")
		(27 "Margin" user)
		(31 "F.CrtYd" user "Package Geometry/Place Bound Top")
		(29 "B.CrtYd" user "Package Geometry/Place Bound Bottom")
		(35 "F.Fab" user "Ref Des/Assembly Top")
		(33 "B.Fab" user "Ref Des/Assembly Bottom")
	)
	(footprint ""
		(layer "B.Cu")
		(at 46.502066 -21.26234 180)
		(property "Reference" "U23"
			(at -1.453134 -2.41681 0)
			(unlocked yes)
			(layer "B.SilkS")
			(effects
				(font
					(size 0.7874 0.5842)
					(thickness 0.1524)
				)
				(justify left mirror)
			)
		)
		(property "Value" ""
			(at 0 0 0)
			(layer "B.Fab")
			(effects
				(font
					(size 1.27 1.27)
				)
				(justify mirror)
			)
		)
		(duplicate_pad_numbers_are_jumpers no)
		(fp_line
			(start 1.733296 1.549908)
			(end -1.733296 1.549908)
			(stroke
				(width 0.1524)
				(type default)
			)
			(layer "B.SilkS")
		)
		(fp_line
			(start 1.733296 -1.549908)
			(end 1.733296 1.549908)
			(stroke
				(width 0.1524)
				(type default)
			)
			(layer "B.SilkS")
		)
		(fp_line
			(start 0.660908 -1.549908)
			(end 1.733296 -1.549908)
			(stroke
				(width 0.1524)
				(type default)
			)
			(layer "B.SilkS")
		)
		(fp_line
			(start 0 -0.889)
			(end 0.660908 -1.549908)
			(stroke
				(width 0.1524)
				(type default)
			)
			(layer "B.SilkS")
		)
		(fp_line
			(start -0.660908 -1.549908)
			(end 0 -0.889)
			(stroke
				(width 0.1524)
				(type default)
			)
			(layer "B.SilkS")
		)
		(fp_line
			(start -1.733296 1.549908)
			(end -1.733296 -1.549908)
			(stroke
				(width 0.1524)
				(type default)
			)
			(layer "B.SilkS")
		)
		(fp_line
			(start -1.733296 -1.549908)
			(end -0.660908 -1.549908)
			(stroke
				(width 0.1524)
				(type default)
			)
			(layer "B.SilkS")
		)
		(fp_poly
			(pts
				(xy 0.977646 -2.547874) (xy 1.485646 -2.547874) (xy 1.231646 -2.039874)
			)
			(stroke
				(width 0)
				(type default)
			)
			(fill yes)
			(layer "B.SilkS")
		)
		(fp_line
			(start 0.849884 1.549908)
			(end -0.849884 1.549908)
			(stroke
				(width 0.1)
				(type default)
			)
			(layer "B.Fab")
		)
		(fp_line
			(start 0.849884 -1.549908)
			(end 0.849884 1.549908)
			(stroke
				(width 0.1)
				(type default)
			)
			(layer "B.Fab")
		)
		(fp_line
			(start -0.849884 1.549908)
			(end -0.849884 -1.549908)
			(stroke
				(width 0.1)
				(type default)
			)
			(layer "B.Fab")
		)
		(fp_line
			(start -0.849884 -1.549908)
			(end 0.849884 -1.549908)
			(stroke
				(width 0.1)
				(type default)
			)
			(layer "B.Fab")
		)
		(fp_poly
			(pts
				(xy 2.4384 -1.20396) (xy 2.4384 -0.69596) (xy 1.9304 -0.94996)
			)
			(stroke
				(width 0)
				(type default)
			)
			(fill yes)
			(layer "B.Fab")
		)
		(pad "1" smd rect
			(at 1.199896 -0.94996 90)
			(size 0.5588 0.8128)
			(layers "B.Cu" "B.Mask" "B.Paste")
			(net "Net_245")
		)
		(pad "2" smd rect
			(at 1.199896 0 90)
			(size 0.5588 0.8128)
			(layers "B.Cu" "B.Mask" "B.Paste")
			(net "DEBUG_PORT_PRSNT")
		)
		(pad "3" smd rect
			(at 1.199896 0.94996 90)
			(size 0.5588 0.8128)
			(layers "B.Cu" "B.Mask" "B.Paste")
			(net "GND")
		)
		(pad "4" smd rect
			(at -1.199896 0.94996 90)
			(size 0.5588 0.8128)
			(layers "B.Cu" "B.Mask" "B.Paste")
			(net "DEBUG_PORT_PRSNT_BUF_R_EN")
		)
		(pad "5" smd rect
			(at -1.199896 -0.94996 90)
			(size 0.5588 0.8128)
			(layers "B.Cu" "B.Mask" "B.Paste")
			(net "P3V3_AUX")
		)
	)
	(footprint ""
		(layer "B.Cu")
		(at 55.499 -34.671 90)
		(property "Reference" "R583"
			(at 0 0 90)
			(layer "B.SilkS")
			(hide yes)
			(effects
				(font
					(size 1.27 1.27)
				)
				(justify mirror)
			)
		)
		(property "Value" ""
			(at 0 0 90)
			(layer "B.Fab")
			(effects
				(font
					(size 1.27 1.27)
				)
				(justify mirror)
			)
		)
		(duplicate_pad_numbers_are_jumpers no)
		(fp_line
			(start 0.7874 -0.4064)
			(end -0.7874 -0.4064)
			(stroke
				(width 0.1524)
				(type default)
			)
			(layer "B.SilkS")
		)
		(fp_line
			(start -0.7874 -0.4064)
			(end -0.7874 0.4064)
			(stroke
				(width 0.1524)
				(type default)
			)
			(layer "B.SilkS")
		)
		(fp_line
			(start 0.7874 0.4064)
			(end 0.7874 -0.4064)
			(stroke
				(width 0.1524)
				(type default)
			)
			(layer "B.SilkS")
		)
		(fp_line
			(start -0.7874 0.4064)
			(end 0.7874 0.4064)
			(stroke
				(width 0.1524)
				(type default)
			)
			(layer "B.SilkS")
		)
		(fp_line
			(start 0.67945 -0.305054)
			(end 0.12065 -0.305054)
			(stroke
				(width 0.1)
				(type default)
			)
			(layer "B.Fab")
		)
		(fp_line
			(start 0.12065 -0.305054)
			(end 0.12065 -0.2794)
			(stroke
				(width 0.1)
				(type default)
			)
			(layer "B.Fab")
		)
		(fp_line
			(start -0.12065 -0.3048)
			(end -0.67945 -0.3048)
			(stroke
				(width 0.1)
				(type default)
			)
			(layer "B.Fab")
		)
		(fp_line
			(start -0.67945 -0.3048)
			(end -0.67945 0.3048)
			(stroke
				(width 0.1)
				(type default)
			)
			(layer "B.Fab")
		)
		(fp_line
			(start 0.12065 -0.2794)
			(end -0.12065 -0.2794)
			(stroke
				(width 0.1)
				(type default)
			)
			(layer "B.Fab")
		)
		(fp_line
			(start -0.12065 -0.2794)
			(end -0.12065 -0.3048)
			(stroke
				(width 0.1)
				(type default)
			)
			(layer "B.Fab")
		)
		(fp_line
			(start 0.12065 0.2794)
			(end 0.12065 0.3048)
			(stroke
				(width 0.1)
				(type default)
			)
			(layer "B.Fab")
		)
		(fp_line
			(start -0.120396 0.2794)
			(end 0.12065 0.2794)
			(stroke
				(width 0.1)
				(type default)
			)
			(layer "B.Fab")
		)
		(fp_line
			(start 0.67945 0.3048)
			(end 0.67945 -0.305054)
			(stroke
				(width 0.1)
				(type default)
			)
			(layer "B.Fab")
		)
		(fp_line
			(start 0.12065 0.3048)
			(end 0.67945 0.3048)
			(stroke
				(width 0.1)
				(type default)
			)
			(layer "B.Fab")
		)
		(fp_line
			(start -0.120396 0.3048)
			(end -0.120396 0.2794)
			(stroke
				(width 0.1)
				(type default)
			)
			(layer "B.Fab")
		)
		(fp_line
			(start -0.67945 0.3048)
			(end -0.120396 0.3048)
			(stroke
				(width 0.1)
				(type default)
			)
			(layer "B.Fab")
		)
		(pad "1" smd circle
			(at 0.40005 0 270)
			(size 0 0)
			(layers "B.Cu" "B.Mask" "B.Paste")
			(net "SMB_BMC_MM10_R_SCL")
		)
		(pad "2" smd circle
			(at -0.40005 0 270)
			(size 0 0)
			(layers "B.Cu" "B.Mask" "B.Paste")
			(net "SMB_BMC_MM10_SCL")
		)
	)
)
